(kicad_pcb
	(version 20260206)
	(generator "pcbnew")
	(generator_version "10.0")
	(general
		(thickness 1.6)
		(legacy_teardrops no)
	)
	(paper "A4")
	(title_block
		(title "01162023_DA0F0TEBIF0_F0T_Expander_BD_F_brd_V02_OCP.brd")
		(comment 1 "Grand Teton / footprints 4798-4804 of 9728")
	)
	(layers
		(0 "F.Cu" signal "TOP")
		(4 "In1.Cu" signal "GND")
		(6 "In2.Cu" signal "VCC")
		(8 "In3.Cu" signal "VCC1")
		(10 "In4.Cu" signal "GND1")
		(12 "In5.Cu" signal "IN1")
		(14 "In6.Cu" signal "GND2")
		(16 "In7.Cu" signal "IN2")
		(18 "In8.Cu" signal "GND3")
		(20 "In9.Cu" signal "IN3")
		(22 "In10.Cu" signal "GND4")
		(24 "In11.Cu" signal "IN4")
		(26 "In12.Cu" signal "GND5")
		(28 "In13.Cu" signal "IN5")
		(30 "In14.Cu" signal "GND6")
		(32 "In15.Cu" signal "IN6")
		(34 "In16.Cu" signal "GND7")
		(2 "B.Cu" signal "BOTTOM")
		(9 "F.Adhes" user "F.Adhesive")
		(11 "B.Adhes" user "B.Adhesive")
		(13 "F.Paste" user "Package Geometry/Pastemask Top")
		(15 "B.Paste" user "Package Geometry/Pastemask Bottom")
		(5 "F.SilkS" user "Ref Des/Silkscreen Top")
		(7 "B.SilkS" user "Ref Des/Silkscreen Bottom")
		(1 "F.Mask" user "Board Geometry/Soldermask Top")
		(3 "B.Mask" user "Board Geometry/Soldermask Bottom")
		(17 "Dwgs.User" user "User.Drawings")
		(19 "Cmts.User" user "User.Comments")
		(21 "Eco1.User" user "User.Eco1")
		(23 "Eco2.User" user "User.Eco2")
		(25 "Edge.Cuts" user "Board Geometry/Outline")
		(27 "Margin" user)
		(31 "F.CrtYd" user "Package Geometry/Place Bound Top")
		(29 "B.CrtYd" user "Package Geometry/Place Bound Bottom")
		(35 "F.Fab" user "Ref Des/Assembly Top")
		(33 "B.Fab" user "Ref Des/Assembly Bottom")
	)
	(footprint ""
		(layer "F.Cu")
		(at 262.353298 -300.992032)
		(property "Reference" "L121"
			(at 0 0 0)
			(layer "F.SilkS")
			(hide yes)
			(effects
				(font
					(size 1.27 1.27)
				)
			)
		)
		(property "Value" ""
			(at 0 0 0)
			(layer "F.Fab")
			(effects
				(font
					(size 1.27 1.27)
				)
			)
		)
		(duplicate_pad_numbers_are_jumpers no)
		(fp_line
			(start -1.63576 -0.8128)
			(end -1.63576 0.8128)
			(stroke
				(width 0.1524)
				(type default)
			)
			(layer "F.SilkS")
		)
		(fp_line
			(start -1.63576 -0.8128)
			(end 1.63576 -0.8128)
			(stroke
				(width 0.1524)
				(type default)
			)
			(layer "F.SilkS")
		)
		(fp_line
			(start 1.63576 -0.8128)
			(end 1.63576 0.8128)
			(stroke
				(width 0.1524)
				(type default)
			)
			(layer "F.SilkS")
		)
		(fp_line
			(start 1.63576 0.8128)
			(end -1.63576 0.8128)
			(stroke
				(width 0.1524)
				(type default)
			)
			(layer "F.SilkS")
		)
		(fp_line
			(start -1.56083 -0.738632)
			(end -1.56083 0.7366)
			(stroke
				(width 0.1)
				(type default)
			)
			(layer "F.Fab")
		)
		(fp_line
			(start -1.56083 0.7366)
			(end -1.524 0.7366)
			(stroke
				(width 0.1)
				(type default)
			)
			(layer "F.Fab")
		)
		(fp_line
			(start -1.524 0.7366)
			(end 1.524 0.7366)
			(stroke
				(width 0.1)
				(type default)
			)
			(layer "F.Fab")
		)
		(fp_line
			(start 1.524 0.7366)
			(end 1.560576 0.7366)
			(stroke
				(width 0.1)
				(type default)
			)
			(layer "F.Fab")
		)
		(fp_line
			(start 1.560576 -0.738632)
			(end -1.56083 -0.738632)
			(stroke
				(width 0.1)
				(type default)
			)
			(layer "F.Fab")
		)
		(fp_line
			(start 1.560576 0.7366)
			(end 1.560576 -0.738632)
			(stroke
				(width 0.1)
				(type default)
			)
			(layer "F.Fab")
		)
		(pad "1" smd rect
			(at -0.94996 0 180)
			(size 1.1176 1.3716)
			(layers "F.Cu" "F.Mask" "F.Paste")
			(net "P1V8_PLL0_PEX2")
		)
		(pad "2" smd rect
			(at 0.94996 0 180)
			(size 1.1176 1.3716)
			(layers "F.Cu" "F.Mask" "F.Paste")
			(net "PCEPLL1_VDDA18_PEX2")
		)
	)
	(footprint ""
		(layer "F.Cu")
		(at 169.759884 -197.900798)
		(property "Reference" "R3288"
			(at 0 0 0)
			(layer "F.SilkS")
			(hide yes)
			(effects
				(font
					(size 1.27 1.27)
				)
			)
		)
		(property "Value" ""
			(at 0 0 0)
			(layer "F.Fab")
			(effects
				(font
					(size 1.27 1.27)
				)
			)
		)
		(duplicate_pad_numbers_are_jumpers no)
		(fp_line
			(start -0.7874 -0.4064)
			(end 0.7874 -0.4064)
			(stroke
				(width 0.1524)
				(type default)
			)
			(layer "F.SilkS")
		)
		(fp_line
			(start -0.7874 0.4064)
			(end -0.7874 -0.4064)
			(stroke
				(width 0.1524)
				(type default)
			)
			(layer "F.SilkS")
		)
		(fp_line
			(start 0.7874 -0.4064)
			(end 0.7874 0.4064)
			(stroke
				(width 0.1524)
				(type default)
			)
			(layer "F.SilkS")
		)
		(fp_line
			(start 0.7874 0.4064)
			(end -0.7874 0.4064)
			(stroke
				(width 0.1524)
				(type default)
			)
			(layer "F.SilkS")
		)
		(fp_line
			(start -0.67945 -0.305054)
			(end -0.12065 -0.305054)
			(stroke
				(width 0.1)
				(type default)
			)
			(layer "F.Fab")
		)
		(fp_line
			(start -0.67945 0.3048)
			(end -0.67945 -0.305054)
			(stroke
				(width 0.1)
				(type default)
			)
			(layer "F.Fab")
		)
		(fp_line
			(start -0.12065 -0.305054)
			(end -0.12065 -0.2794)
			(stroke
				(width 0.1)
				(type default)
			)
			(layer "F.Fab")
		)
		(fp_line
			(start -0.12065 -0.2794)
			(end 0.12065 -0.2794)
			(stroke
				(width 0.1)
				(type default)
			)
			(layer "F.Fab")
		)
		(fp_line
			(start -0.12065 0.2794)
			(end -0.12065 0.3048)
			(stroke
				(width 0.1)
				(type default)
			)
			(layer "F.Fab")
		)
		(fp_line
			(start -0.12065 0.3048)
			(end -0.67945 0.3048)
			(stroke
				(width 0.1)
				(type default)
			)
			(layer "F.Fab")
		)
		(fp_line
			(start 0.120396 0.2794)
			(end -0.12065 0.2794)
			(stroke
				(width 0.1)
				(type default)
			)
			(layer "F.Fab")
		)
		(fp_line
			(start 0.120396 0.3048)
			(end 0.120396 0.2794)
			(stroke
				(width 0.1)
				(type default)
			)
			(layer "F.Fab")
		)
		(fp_line
			(start 0.12065 -0.3048)
			(end 0.67945 -0.3048)
			(stroke
				(width 0.1)
				(type default)
			)
			(layer "F.Fab")
		)
		(fp_line
			(start 0.12065 -0.2794)
			(end 0.12065 -0.3048)
			(stroke
				(width 0.1)
				(type default)
			)
			(layer "F.Fab")
		)
		(fp_line
			(start 0.67945 -0.3048)
			(end 0.67945 0.3048)
			(stroke
				(width 0.1)
				(type default)
			)
			(layer "F.Fab")
		)
		(fp_line
			(start 0.67945 0.3048)
			(end 0.120396 0.3048)
			(stroke
				(width 0.1)
				(type default)
			)
			(layer "F.Fab")
		)
		(pad "1" smd circle
			(at -0.40005 0)
			(size 0 0)
			(layers "F.Cu" "F.Mask" "F.Paste")
			(net "SPI_BIC1_CLK_LS01_R")
		)
		(pad "2" smd circle
			(at 0.40005 0)
			(size 0 0)
			(layers "F.Cu" "F.Mask" "F.Paste")
			(net "SPI_BIC1_CLK_LS01")
		)
	)
	(footprint ""
		(layer "F.Cu")
		(at 296.766742 -356.244906 90)
		(property "Reference" "C586"
			(at 0 0 90)
			(layer "F.SilkS")
			(hide yes)
			(effects
				(font
					(size 1.27 1.27)
				)
			)
		)
		(property "Value" ""
			(at 0 0 90)
			(layer "F.Fab")
			(effects
				(font
					(size 1.27 1.27)
				)
			)
		)
		(duplicate_pad_numbers_are_jumpers no)
		(fp_line
			(start 0.299974 -0.150114)
			(end 0.299974 0.150114)
			(stroke
				(width 0.1)
				(type default)
			)
			(layer "F.Fab")
		)
		(fp_line
			(start -0.299974 -0.150114)
			(end 0.299974 -0.150114)
			(stroke
				(width 0.1)
				(type default)
			)
			(layer "F.Fab")
		)
		(fp_line
			(start 0.299974 0.150114)
			(end -0.299974 0.150114)
			(stroke
				(width 0.1)
				(type default)
			)
			(layer "F.Fab")
		)
		(fp_line
			(start -0.299974 0.150114)
			(end -0.299974 -0.150114)
			(stroke
				(width 0.1)
				(type default)
			)
			(layer "F.Fab")
		)
		(pad "1" smd rect
			(at -0.2667 0 90)
			(size 0.3048 0.381)
			(layers "F.Cu" "F.Mask" "F.Paste")
			(net "P5E_PEX2_STN7_TX_DN<126>")
		)
		(pad "2" smd rect
			(at 0.2667 0 90)
			(size 0.3048 0.381)
			(layers "F.Cu" "F.Mask" "F.Paste")
			(net "P5E_PEX2_STN7_TX_C_DN<126>")
		)
	)
	(footprint ""
		(layer "F.Cu")
		(at 105.27157 -280.44902 -90)
		(property "Reference" "PR100"
			(at 0 0 270)
			(layer "F.SilkS")
			(hide yes)
			(effects
				(font
					(size 1.27 1.27)
				)
			)
		)
		(property "Value" ""
			(at 0 0 270)
			(layer "F.Fab")
			(effects
				(font
					(size 1.27 1.27)
				)
			)
		)
		(duplicate_pad_numbers_are_jumpers no)
		(fp_line
			(start -0.7874 0.4064)
			(end -0.7874 -0.4064)
			(stroke
				(width 0.1524)
				(type default)
			)
			(layer "F.SilkS")
		)
		(fp_line
			(start 0.7874 0.4064)
			(end -0.7874 0.4064)
			(stroke
				(width 0.1524)
				(type default)
			)
			(layer "F.SilkS")
		)
		(fp_line
			(start -0.7874 -0.4064)
			(end 0.7874 -0.4064)
			(stroke
				(width 0.1524)
				(type default)
			)
			(layer "F.SilkS")
		)
		(fp_line
			(start 0.7874 -0.4064)
			(end 0.7874 0.4064)
			(stroke
				(width 0.1524)
				(type default)
			)
			(layer "F.SilkS")
		)
		(fp_line
			(start -0.67945 0.3048)
			(end -0.67945 -0.305054)
			(stroke
				(width 0.1)
				(type default)
			)
			(layer "F.Fab")
		)
		(fp_line
			(start -0.12065 0.3048)
			(end -0.67945 0.3048)
			(stroke
				(width 0.1)
				(type default)
			)
			(layer "F.Fab")
		)
		(fp_line
			(start 0.120396 0.3048)
			(end 0.120396 0.2794)
			(stroke
				(width 0.1)
				(type default)
			)
			(layer "F.Fab")
		)
		(fp_line
			(start 0.67945 0.3048)
			(end 0.120396 0.3048)
			(stroke
				(width 0.1)
				(type default)
			)
			(layer "F.Fab")
		)
		(fp_line
			(start -0.12065 0.2794)
			(end -0.12065 0.3048)
			(stroke
				(width 0.1)
				(type default)
			)
			(layer "F.Fab")
		)
		(fp_line
			(start 0.120396 0.2794)
			(end -0.12065 0.2794)
			(stroke
				(width 0.1)
				(type default)
			)
			(layer "F.Fab")
		)
		(fp_line
			(start -0.12065 -0.2794)
			(end 0.12065 -0.2794)
			(stroke
				(width 0.1)
				(type default)
			)
			(layer "F.Fab")
		)
		(fp_line
			(start 0.12065 -0.2794)
			(end 0.12065 -0.3048)
			(stroke
				(width 0.1)
				(type default)
			)
			(layer "F.Fab")
		)
		(fp_line
			(start 0.12065 -0.3048)
			(end 0.67945 -0.3048)
			(stroke
				(width 0.1)
				(type default)
			)
			(layer "F.Fab")
		)
		(fp_line
			(start 0.67945 -0.3048)
			(end 0.67945 0.3048)
			(stroke
				(width 0.1)
				(type default)
			)
			(layer "F.Fab")
		)
		(fp_line
			(start -0.67945 -0.305054)
			(end -0.12065 -0.305054)
			(stroke
				(width 0.1)
				(type default)
			)
			(layer "F.Fab")
		)
		(fp_line
			(start -0.12065 -0.305054)
			(end -0.12065 -0.2794)
			(stroke
				(width 0.1)
				(type default)
			)
			(layer "F.Fab")
		)
		(pad "1" smd circle
			(at -0.40005 0 270)
			(size 0 0)
			(layers "F.Cu" "F.Mask" "F.Paste")
			(net "SW_P0V8_PEX0_BOOT1")
		)
		(pad "2" smd circle
			(at 0.40005 0 270)
			(size 0 0)
			(layers "F.Cu" "F.Mask" "F.Paste")
			(net "SW_P0V8_PEX0_BOOT1_R")
		)
	)
	(footprint ""
		(layer "F.Cu")
		(at 264.517632 -113.558574 -90)
		(property "Reference" "C4002"
			(at 0 0 270)
			(layer "F.SilkS")
			(hide yes)
			(effects
				(font
					(size 1.27 1.27)
				)
			)
		)
		(property "Value" ""
			(at 0 0 270)
			(layer "F.Fab")
			(effects
				(font
					(size 1.27 1.27)
				)
			)
		)
		(duplicate_pad_numbers_are_jumpers no)
		(fp_line
			(start -0.7874 0.4064)
			(end -0.7874 -0.4064)
			(stroke
				(width 0.1524)
				(type default)
			)
			(layer "F.SilkS")
		)
		(fp_line
			(start 0.7874 0.4064)
			(end -0.7874 0.4064)
			(stroke
				(width 0.1524)
				(type default)
			)
			(layer "F.SilkS")
		)
		(fp_line
			(start -0.7874 -0.4064)
			(end 0.7874 -0.4064)
			(stroke
				(width 0.1524)
				(type default)
			)
			(layer "F.SilkS")
		)
		(fp_line
			(start 0.7874 -0.4064)
			(end 0.7874 0.4064)
			(stroke
				(width 0.1524)
				(type default)
			)
			(layer "F.SilkS")
		)
		(fp_line
			(start -0.67945 0.3048)
			(end -0.67945 -0.305054)
			(stroke
				(width 0.1)
				(type default)
			)
			(layer "F.Fab")
		)
		(fp_line
			(start -0.12065 0.3048)
			(end -0.67945 0.3048)
			(stroke
				(width 0.1)
				(type default)
			)
			(layer "F.Fab")
		)
		(fp_line
			(start 0.120396 0.3048)
			(end 0.120396 0.2794)
			(stroke
				(width 0.1)
				(type default)
			)
			(layer "F.Fab")
		)
		(fp_line
			(start 0.67945 0.3048)
			(end 0.120396 0.3048)
			(stroke
				(width 0.1)
				(type default)
			)
			(layer "F.Fab")
		)
		(fp_line
			(start -0.12065 0.2794)
			(end -0.12065 0.3048)
			(stroke
				(width 0.1)
				(type default)
			)
			(layer "F.Fab")
		)
		(fp_line
			(start 0.120396 0.2794)
			(end -0.12065 0.2794)
			(stroke
				(width 0.1)
				(type default)
			)
			(layer "F.Fab")
		)
		(fp_line
			(start -0.12065 -0.2794)
			(end 0.12065 -0.2794)
			(stroke
				(width 0.1)
				(type default)
			)
			(layer "F.Fab")
		)
		(fp_line
			(start 0.12065 -0.2794)
			(end 0.12065 -0.3048)
			(stroke
				(width 0.1)
				(type default)
			)
			(layer "F.Fab")
		)
		(fp_line
			(start 0.12065 -0.3048)
			(end 0.67945 -0.3048)
			(stroke
				(width 0.1)
				(type default)
			)
			(layer "F.Fab")
		)
		(fp_line
			(start 0.67945 -0.3048)
			(end 0.67945 0.3048)
			(stroke
				(width 0.1)
				(type default)
			)
			(layer "F.Fab")
		)
		(fp_line
			(start -0.67945 -0.305054)
			(end -0.12065 -0.305054)
			(stroke
				(width 0.1)
				(type default)
			)
			(layer "F.Fab")
		)
		(fp_line
			(start -0.12065 -0.305054)
			(end -0.12065 -0.2794)
			(stroke
				(width 0.1)
				(type default)
			)
			(layer "F.Fab")
		)
		(pad "1" smd circle
			(at -0.40005 0 270)
			(size 0 0)
			(layers "F.Cu" "F.Mask" "F.Paste")
			(net "PRSNT_NIC4_R_N")
		)
		(pad "2" smd circle
			(at 0.40005 0 270)
			(size 0 0)
			(layers "F.Cu" "F.Mask" "F.Paste")
			(net "GND")
		)
	)
	(footprint ""
		(layer "F.Cu")
		(at 366.955578 -88.356694 180)
		(property "Reference" "R1628"
			(at 0 0 180)
			(layer "F.SilkS")
			(hide yes)
			(effects
				(font
					(size 1.27 1.27)
				)
			)
		)
		(property "Value" ""
			(at 0 0 180)
			(layer "F.Fab")
			(effects
				(font
					(size 1.27 1.27)
				)
			)
		)
		(duplicate_pad_numbers_are_jumpers no)
		(fp_line
			(start 0.7874 0.4064)
			(end -0.7874 0.4064)
			(stroke
				(width 0.1524)
				(type default)
			)
			(layer "F.SilkS")
		)
		(fp_line
			(start 0.7874 -0.4064)
			(end 0.7874 0.4064)
			(stroke
				(width 0.1524)
				(type default)
			)
			(layer "F.SilkS")
		)
		(fp_line
			(start -0.7874 0.4064)
			(end -0.7874 -0.4064)
			(stroke
				(width 0.1524)
				(type default)
			)
			(layer "F.SilkS")
		)
		(fp_line
			(start -0.7874 -0.4064)
			(end 0.7874 -0.4064)
			(stroke
				(width 0.1524)
				(type default)
			)
			(layer "F.SilkS")
		)
		(fp_line
			(start 0.67945 0.3048)
			(end 0.120396 0.3048)
			(stroke
				(width 0.1)
				(type default)
			)
			(layer "F.Fab")
		)
		(fp_line
			(start 0.67945 -0.3048)
			(end 0.67945 0.3048)
			(stroke
				(width 0.1)
				(type default)
			)
			(layer "F.Fab")
		)
		(fp_line
			(start 0.12065 -0.2794)
			(end 0.12065 -0.3048)
			(stroke
				(width 0.1)
				(type default)
			)
			(layer "F.Fab")
		)
		(fp_line
			(start 0.12065 -0.3048)
			(end 0.67945 -0.3048)
			(stroke
				(width 0.1)
				(type default)
			)
			(layer "F.Fab")
		)
		(fp_line
			(start 0.120396 0.3048)
			(end 0.120396 0.2794)
			(stroke
				(width 0.1)
				(type default)
			)
			(layer "F.Fab")
		)
		(fp_line
			(start 0.120396 0.2794)
			(end -0.12065 0.2794)
			(stroke
				(width 0.1)
				(type default)
			)
			(layer "F.Fab")
		)
		(fp_line
			(start -0.12065 0.3048)
			(end -0.67945 0.3048)
			(stroke
				(width 0.1)
				(type default)
			)
			(layer "F.Fab")
		)
		(fp_line
			(start -0.12065 0.2794)
			(end -0.12065 0.3048)
			(stroke
				(width 0.1)
				(type default)
			)
			(layer "F.Fab")
		)
		(fp_line
			(start -0.12065 -0.2794)
			(end 0.12065 -0.2794)
			(stroke
				(width 0.1)
				(type default)
			)
			(layer "F.Fab")
		)
		(fp_line
			(start -0.12065 -0.305054)
			(end -0.12065 -0.2794)
			(stroke
				(width 0.1)
				(type default)
			)
			(layer "F.Fab")
		)
		(fp_line
			(start -0.67945 0.3048)
			(end -0.67945 -0.305054)
			(stroke
				(width 0.1)
				(type default)
			)
			(layer "F.Fab")
		)
		(fp_line
			(start -0.67945 -0.305054)
			(end -0.12065 -0.305054)
			(stroke
				(width 0.1)
				(type default)
			)
			(layer "F.Fab")
		)
		(pad "1" smd circle
			(at -0.40005 0 180)
			(size 0 0)
			(layers "F.Cu" "F.Mask" "F.Paste")
			(net "SMB_BIC_I2C9_MUX1_SSD15_R_SDA")
		)
		(pad "2" smd circle
			(at 0.40005 0 180)
			(size 0 0)
			(layers "F.Cu" "F.Mask" "F.Paste")
			(net "SMB_BIC_I2C9_MUX1_SSD15_SDA")
		)
	)
	(footprint ""
		(layer "F.Cu")
		(at 225.530664 -207.02016 90)
		(property "Reference" "R5278"
			(at 0 0 90)
			(layer "F.SilkS")
			(hide yes)
			(effects
				(font
					(size 1.27 1.27)
				)
			)
		)
		(property "Value" ""
			(at 0 0 90)
			(layer "F.Fab")
			(effects
				(font
					(size 1.27 1.27)
				)
			)
		)
		(duplicate_pad_numbers_are_jumpers no)
		(fp_line
			(start 0.7874 -0.4064)
			(end 0.7874 0.4064)
			(stroke
				(width 0.1524)
				(type default)
			)
			(layer "F.SilkS")
		)
		(fp_line
			(start -0.7874 -0.4064)
			(end 0.7874 -0.4064)
			(stroke
				(width 0.1524)
				(type default)
			)
			(layer "F.SilkS")
		)
		(fp_line
			(start 0.7874 0.4064)
			(end -0.7874 0.4064)
			(stroke
				(width 0.1524)
				(type default)
			)
			(layer "F.SilkS")
		)
		(fp_line
			(start -0.7874 0.4064)
			(end -0.7874 -0.4064)
			(stroke
				(width 0.1524)
				(type default)
			)
			(layer "F.SilkS")
		)
		(fp_line
			(start -0.12065 -0.305054)
			(end -0.12065 -0.2794)
			(stroke
				(width 0.1)
				(type default)
			)
			(layer "F.Fab")
		)
		(fp_line
			(start -0.67945 -0.305054)
			(end -0.12065 -0.305054)
			(stroke
				(width 0.1)
				(type default)
			)
			(layer "F.Fab")
		)
		(fp_line
			(start 0.67945 -0.3048)
			(end 0.67945 0.3048)
			(stroke
				(width 0.1)
				(type default)
			)
			(layer "F.Fab")
		)
		(fp_line
			(start 0.12065 -0.3048)
			(end 0.67945 -0.3048)
			(stroke
				(width 0.1)
				(type default)
			)
			(layer "F.Fab")
		)
		(fp_line
			(start 0.12065 -0.2794)
			(end 0.12065 -0.3048)
			(stroke
				(width 0.1)
				(type default)
			)
			(layer "F.Fab")
		)
		(fp_line
			(start -0.12065 -0.2794)
			(end 0.12065 -0.2794)
			(stroke
				(width 0.1)
				(type default)
			)
			(layer "F.Fab")
		)
		(fp_line
			(start 0.120396 0.2794)
			(end -0.12065 0.2794)
			(stroke
				(width 0.1)
				(type default)
			)
			(layer "F.Fab")
		)
		(fp_line
			(start -0.12065 0.2794)
			(end -0.12065 0.3048)
			(stroke
				(width 0.1)
				(type default)
			)
			(layer "F.Fab")
		)
		(fp_line
			(start 0.67945 0.3048)
			(end 0.120396 0.3048)
			(stroke
				(width 0.1)
				(type default)
			)
			(layer "F.Fab")
		)
		(fp_line
			(start 0.120396 0.3048)
			(end 0.120396 0.2794)
			(stroke
				(width 0.1)
				(type default)
			)
			(layer "F.Fab")
		)
		(fp_line
			(start -0.12065 0.3048)
			(end -0.67945 0.3048)
			(stroke
				(width 0.1)
				(type default)
			)
			(layer "F.Fab")
		)
		(fp_line
			(start -0.67945 0.3048)
			(end -0.67945 -0.305054)
			(stroke
				(width 0.1)
				(type default)
			)
			(layer "F.Fab")
		)
		(pad "1" smd circle
			(at -0.40005 0 90)
			(size 0 0)
			(layers "F.Cu" "F.Mask" "F.Paste")
			(net "JTAG_BIC_NTRST_R_N")
		)
		(pad "2" smd circle
			(at 0.40005 0 90)
			(size 0 0)
			(layers "F.Cu" "F.Mask" "F.Paste")
			(net "JTAG_BIC_NTRST_N")
		)
	)
)
